# TIMECARD (Time Appliance Project (Time Card)) — schematic netlist excerpt (pin names and nets, part order shuffled) for the footprints in the layout excerpt that follows; sources: Cadence DE-HDL packaged netlist, KiCad conversion of R4006-B0001-02_R01.brd

R398  RESISTOR  33OHM 1%  pkg SMC_0402R_H016  page 26 : \1\ = GPS_SMA_LED_GREEN_N ; \2\ = UNNAMED_14_LED4PV14_I269_4

(kicad_pcb
	(version 20260206)
	(generator "pcbnew")
	(generator_version "10.0")
	(general
		(thickness 1.6)
		(legacy_teardrops no)
	)
	(paper "A4")
	(title_block
		(title "timecard-production-celestica-r4006 — R4006-B0001-02_R01.brd")
		(comment 1 "Time Appliance Project (Time Card) / footprints 87-87 of 1113")
	)
	(layers
		(0 "F.Cu" signal "TOP")
		(4 "In1.Cu" signal "L02_GND1")
		(6 "In2.Cu" signal "L03_SIG1")
		(8 "In3.Cu" signal "L04_GND2")
		(10 "In4.Cu" signal "L05_VCC1")
		(12 "In5.Cu" signal "L06_VCC2")
		(14 "In6.Cu" signal "L07_GND3")
		(16 "In7.Cu" signal "L08_SIG2")
		(18 "In8.Cu" signal "L09_GND4")
		(2 "B.Cu" signal "BOTTOM")
		(9 "F.Adhes" user "F.Adhesive")
		(11 "B.Adhes" user "B.Adhesive")
		(13 "F.Paste" user "Package Geometry/Pastemask Top")
		(15 "B.Paste" user "Package Geometry/Pastemask Bottom")
		(5 "F.SilkS" user "Ref Des/Silkscreen Top")
		(7 "B.SilkS" user "Ref Des/Silkscreen Bottom")
		(1 "F.Mask" user "Board Geometry/Soldermask Top")
		(3 "B.Mask" user "Board Geometry/Soldermask Bottom")
		(17 "Dwgs.User" user "User.Drawings")
		(19 "Cmts.User" user "User.Comments")
		(21 "Eco1.User" user "User.Eco1")
		(23 "Eco2.User" user "User.Eco2")
		(25 "Edge.Cuts" user "Board Geometry/Outline")
		(27 "Margin" user)
		(31 "F.CrtYd" user "Package Geometry/Place Bound Top")
		(29 "B.CrtYd" user "Package Geometry/Place Bound Bottom")
		(35 "F.Fab" user "Ref Des/Assembly Top")
		(33 "B.Fab" user "Ref Des/Assembly Bottom")
	)
	(footprint ""
		(layer "F.Cu")
		(at 10.922 -81.534 90)
		(property "Reference" "R398"
			(at -2.667 1.05537 90)
			(unlocked yes)
			(layer "F.SilkS")
			(effects
				(font
					(size 0.7874 0.5842)
					(thickness 0.1524)
				)
			)
		)
		(property "Value" "VAL*"
			(at 0.02032 2.13233 90)
			(unlocked yes)
			(layer "F.Fab")
			(hide yes)
			(effects
				(font
					(size 0.7874 0.5842)
					(thickness 0.1524)
				)
			)
		)
		(property "Tolerance" "TOL*"
			(at 0.044704 3.05435 90)
			(unlocked yes)
			(layer "Cmts.User")
			(hide yes)
			(effects
				(font
					(size 0.7874 0.5842)
					(thickness 0.1524)
				)
			)
		)
		(property "User Part Number" "PARTNUM*"
			(at 0.02032 4.024884 90)
			(unlocked yes)
			(layer "Cmts.User")
			(hide yes)
			(effects
				(font
					(size 0.7874 0.5842)
					(thickness 0.1524)
				)
			)
		)
		(property "Device Type" "RESISTOR-G155-133R0-01,33OHM,1%"
			(at 0.008382 1.210564 90)
			(unlocked yes)
			(layer "F.Fab")
			(hide yes)
			(effects
				(font
					(size 0.7874 0.5842)
					(thickness 0.1524)
				)
			)
		)
		(duplicate_pad_numbers_are_jumpers no)
		(fp_line
			(start 1.143 -0.5588)
			(end -1.143 -0.5588)
			(stroke
				(width 0.1)
				(type default)
			)
			(layer "F.SilkS")
		)
		(fp_line
			(start -1.143 -0.5588)
			(end -1.143 0.5588)
			(stroke
				(width 0.1)
				(type default)
			)
			(layer "F.SilkS")
		)
		(fp_line
			(start 1.143 0.5588)
			(end 1.143 -0.5588)
			(stroke
				(width 0.1)
				(type default)
			)
			(layer "F.SilkS")
		)
		(fp_line
			(start -1.143 0.5588)
			(end 1.143 0.5588)
			(stroke
				(width 0.1)
				(type default)
			)
			(layer "F.SilkS")
		)
		(fp_rect
			(start -1.143 -0.5588)
			(end 1.143 0.5588)
			(stroke
				(width 0)
				(type default)
			)
			(fill no)
			(layer "F.CrtYd")
		)
		(fp_line
			(start 0.508 -0.3048)
			(end -0.508 -0.3048)
			(stroke
				(width 0.1)
				(type default)
			)
			(layer "F.Fab")
		)
		(fp_line
			(start -0.508 -0.3048)
			(end -0.508 0.3048)
			(stroke
				(width 0.1)
				(type default)
			)
			(layer "F.Fab")
		)
		(fp_line
			(start 0.508 0.3048)
			(end 0.508 -0.3048)
			(stroke
				(width 0.1)
				(type default)
			)
			(layer "F.Fab")
		)
		(fp_line
			(start -0.508 0.3048)
			(end 0.508 0.3048)
			(stroke
				(width 0.1)
				(type default)
			)
			(layer "F.Fab")
		)
		(pad "1" smd rect
			(at -0.5334 0 90)
			(size 0.7112 0.6096)
			(layers "F.Cu" "F.Mask" "F.Paste")
			(net "GPS_SMA_LED_GREEN_N")
		)
		(pad "2" smd rect
			(at 0.5334 0 90)
			(size 0.7112 0.6096)
			(layers "F.Cu" "F.Mask" "F.Paste")
			(net "UNNAMED_14_LED4PV14_I269_4")
		)
		(zone
			(layer "F.Cu")
			(hatch none 0.5)
			(connect_pads
				(clearance 0)
			)
			(min_thickness 0.25)
			(keepout
				(tracks not_allowed)
				(vias allowed)
				(pads allowed)
				(copperpour not_allowed)
				(footprints allowed)
			)
			(placement
				(enabled no)
				(sheetname "")
			)
			(fill
				(thermal_gap 0.5)
				(thermal_bridge_width 0.5)
				(island_removal_mode 0)
			)
			(polygon
				(pts
					(xy 10.6172 -81.4578) (xy 11.2268 -81.4578) (xy 11.2268 -81.6102) (xy 10.6172 -81.6102)
				)
			)
		)
		(zone
			(layer "F.Cu")
			(hatch none 0.5)
			(connect_pads
				(clearance 0)
			)
			(min_thickness 0.25)
			(keepout
				(tracks allowed)
				(vias not_allowed)
				(pads allowed)
				(copperpour not_allowed)
				(footprints allowed)
			)
			(placement
				(enabled no)
				(sheetname "")
			)
			(fill
				(thermal_gap 0.5)
				(thermal_bridge_width 0.5)
				(island_removal_mode 0)
			)
			(polygon
				(pts
					(xy 10.6172 -81.4578) (xy 11.2268 -81.4578) (xy 11.2268 -81.6102) (xy 10.6172 -81.6102)
				)
			)
		)
	)
)
